 
 
 
 
Open CloudServer  
OCS Chassis Power Supply 
2.0 
 
 
 
 
 
Author: 
Shaun Harris, Director of Mechanical and Power Engineering, Microsoft 
 



Open Compute Project  Open CloudServer OCS Chassis Power Supply 
http://opencompute.org ii 
Revision History 
Date Description 
1/20/2015 Version 2.0 
 
  



Open Compute Project  Open CloudServer OCS Power Supply 
http://opencompute.org iii 
 
© 2015 Microsoft Corporation. 
As of October 30, 2014, the following persons or entities have made this Specification available under the Open Web 
Foundation Final Specification Agreement (OWFa 1.0), which is available at http://www.openwebfoundation.org/legal/the-owf-
1-0-agreements/owfa-1-0 
 Microsoft Corporation.  
You can review the signed copies of the Open Web Foundation Agreement Version 1.0 for this Specification at 
http://opencompute.org/licensing/, which may also include additional parties to those listed above. 
Your use of this Specification may be subject to other third party rights. THIS SPECIFICATION IS PROVIDED "AS IS." The 
contributors expressly disclaim any warranties (express, implied, or otherwise), including implied warranties of merchantability, 
noninfringement, fitness for a particular purpose, or title, related to the Specification. The entire risk as to implementing or 
otherwise using the Specification is assumed by the Specification implementer and user. IN NO EVENT WILL ANY PARTY BE 
LIABLE TO ANY OTHER PARTY FOR LOST PROFITS OR ANY FORM OF INDIRECT, SPECIAL, INCIDENTAL, OR CONSEQUENTIAL 
DAMAGES OF ANY CHARACTER FROM ANY CAUSES OF ACTION OF ANY KIND WITH RESPECT TO THIS SPECIFICATION OR ITS 
GOVERNING AGREEMENT, WHETHER BASED ON BREACH OF CONTRACT, TORT (INCLUDING NEGLIGENCE), OR OTHERWISE, AND 
WHETHER OR NOT THE OTHER PARTY HAS BEEN ADVISED OF THE POSSIBILITY OF SUCH DAMAGE. 
CONTRIBUTORS AND LICENSORS OF THIS SPECIFICATION MAY HAVE MENTIONED CERTAIN TECHNOLOGIES THAT ARE MERELY 
REFERENCED WITHIN THIS SPECIFICATION AND NOT LICENSED UNDER THE OWF CLA OR OWFa. THE FOLLOWING IS A LIST OF 
MERELY REFERENCED TECHNOLOGY: INTELLIGENT PLATFORM MANAGEMENT INTERFACE (IPMI), I2C TRADEMARK OF PHILLIPS 
SEMICONDUCTOR. IMPLEMENTATION OF THESE TECHNOLOGIES MAY BE SUBJECT TO THEIR OWN LEGAL TERMS. 
  



 
iv January 20, 2015 
 
 
Contents 
1 Summary ....................................................................................................................................................... 1 
2 Reference Documents ................................................................................................................................... 1 
2.1 Applicable Documents .................................................................................................................................. 1 
2.2 Order of Preference ...................................................................................................................................... 3 
3 Electrical Specification ................................................................................................................................... 3 
3.1 AC Input ........................................................................................................................................................ 3 
3.1.1 Voltage, Current, and Frequency ............................................................................................................. 3 
3.1.2 Hold-Up Time ........................................................................................................................................... 4 
3.1.3 AC Turn On Requirement ......................................................................................................................... 4 
3.1.4 AC Turn Off Brownout Requirement ....................................................................................................... 5 
3.1.5 AC Line Fuse ............................................................................................................................................. 5 
3.1.6 AC Inlet Connector ................................................................................................................................... 5 
3.1.7 Input Leakage Current ............................................................................................................................. 5 
3.1.8 Input Power Rating .................................................................................................................................. 5 
3.1.9 Inrush Current .......................................................................................................................................... 5 
3.1.10 Power Factor ....................................................................................................................................... 6 
3.1.11 Harmonic Susceptibility ....................................................................................................................... 6 
3.1.12 Modified Sine Waves ........................................................................................................................... 6 
3.1.13 Harmonic Emissions ............................................................................................................................ 6 
3.1.14 Line Transient ...................................................................................................................................... 7 
3.1.15 Electrostatic Discharge Susceptibility .................................................................................................. 7 
3.1.16 Fast Transient Burst ............................................................................................................................. 7 
3.1.17 Radiated Immunity .............................................................................................................................. 7 
3.1.18 Surge Immunity ................................................................................................................................... 7 
3.1.19 Efficiency ............................................................................................................................................. 8 
3.2 Battery Backup Operation ............................................................................................................................ 8 
3.3 DC Outputs, Signal Outputs, and Control Outputs ..................................................................................... 10 
3.3.1 Output Power and Current .................................................................................................................... 10 
3.3.2 Output ORing ......................................................................................................................................... 10 
3.3.3 Standby Output ...................................................................................................................................... 10 
3.3.4 Setpoint.................................................................................................................................................. 10 
3.3.5 Static Voltage Regulation ....................................................................................................................... 11 
3.3.6 Ripple and Noise .................................................................................................................................... 11 
3.3.7 Dynamic Load Step ................................................................................................................................ 11 
3.3.8 Capacitive Loading ................................................................................................................................. 11 
3.3.9 Closed Loop Stability .............................................................................................................................. 11 
3.3.10 Grounding .......................................................................................................................................... 12 
3.3.11 Common Mode Noise ........................................................................................................................ 12 
3.3.12 Soft Start ............................................................................................................................................ 12 
3.3.13 Zero Load Stability ............................................................................................................................. 12 



Open Compute Project  Open CloudServer OCS Power Supply 
http://opencompute.org v 
 
3.3.14 Hot Swap Requirements .................................................................................................................... 12 
3.3.15 Forced Load Sharing .......................................................................................................................... 12 
4 PSU System Interconnect ............................................................................................................................ 13 
4.1 Remote On/Off ........................................................................................................................................... 13 
4.2 Power Good Signal ..................................................................................................................................... 13 
4.3 Fan Speed Control ...................................................................................................................................... 13 
4.4 VIN_Good Signal ........................................................................................................................................ 14 
4.5 I-Share ........................................................................................................................................................ 14 
4.6 I2C/PMBus .................................................................................................................................................. 14 
4.7 PS_KILL/EPO ............................................................................................................................................... 14 
4.8 PSU Alert .................................................................................................................................................... 15 
Note 1: Pull up to 3.3V through 100K ohms ............................................................................................................ 15 
4.9 Power Supply Present ................................................................................................................................. 15 
4.10 Phase Loss Detect ....................................................................................................................................... 15 
4.11 Output Connector Pinout ........................................................................................................................... 16 
4.12 Protection Circuits ...................................................................................................................................... 16 
4.12.1 Over Current Limit (OCL) ................................................................................................................... 17 
4.12.2 Over Voltage Protection (OVP) .......................................................................................................... 17 
4.12.3 Over Temperature Protection (OTP) ................................................................................................. 17 
5 LED Indicators .............................................................................................................................................. 17 
6 Mechanical Specifications ........................................................................................................................... 18 
6.1 Dimensions ................................................................................................................................................. 18 
6.2 Core Handle Retention ............................................................................................................................... 19 
6.3 Electrostatic Discharge ............................................................................................................................... 19 
7 Agency Approvals and Product Regulatory Requirements ........................................................................... 19 
7.1 Safety Requirements and Approvals .......................................................................................................... 20 
7.2 EMC Requirements and Approvals ............................................................................................................. 20 
7.3 Component Regulation Requirements ....................................................................................................... 20 
7.4 Product EMC Compliance ........................................................................................................................... 21 
7.5 Markings and Identification ....................................................................................................................... 21 
 
  



 
vi January 20, 2015 
 
Table of Figures 
Figure 1: Timing diagram .............................................................................................................................. 9 
Figure 3: Output connector pinout ............................................................................................................. 16 
Figure 5: Dimension detail (side) ................................................................................................................ 18 
Figure 6: Additional detail ........................................................................................................................... 19 
 
  



Open Compute Project  Open CloudServer OCS Power Supply 
http://opencompute.org vii 
 
Table of Tables 
Table 1: Applicable Documents .................................................................................................................... 1 
Table 2: AC Input Rating ................................................................................................................................ 3 
Table 3: THD Requirements .......................................................................................................................... 6 
Table 4: Efficiency ......................................................................................................................................... 8 
Table 5: Output Power and Current............................................................................................................ 10 
Table 6: Setpoints ....................................................................................................................................... 10 
Table 7: Static Voltage ................................................................................................................................ 11 
Table 8: Dynamic Load Step ........................................................................................................................ 11 
Table 9: Capacitive Loading ........................................................................................................................ 11 
Table 10: Power On/Off .............................................................................................................................. 13 
Table 11: Power Good ................................................................................................................................. 13 
Table 12: VIN_Good Signal .......................................................................................................................... 14 
Table 13: I2C/PMBus ................................................................................................................................... 14 
Table 14: PS_Kill .......................................................................................................................................... 15 
Table 15: PSU Alert ..................................................................................................................................... 15 
Table 16: PS_Present .................................................................................................................................. 15 




 
http://opencompute.org 1 
 
1 Summary 
This specification, Open CloudServer Chassis Power Supply Version 2.0, describes the power supply 
family requirements for the Windows Cloud Server system. The mechanical interface and electrical 
interface is identical between power supply options to enable a common slot, universal, modular 
foundation power supply system to enable the Microsoft Windows Cloud Server systems. The product 
family encompasses a power supply output power with the option of adding Local Energy Storage (LES) 
to the parameters offered in the specification: 
 Single Phase 1600W 12VDC Power Supply (Version 1) 
 Single Phase 1600W 12VDC Power Supply with Local Energy Storage (LES) (Version 2) 
The power supply is to be used in a high line only, single phase input, redundant power system design 
with N=5, N+1=6 configuration. The power supply shall be hot pluggable. 
Note:  Unless otherwise specified, all requirements in this specification shall be met for version 1 and 2 
listed above.  Where power supplies differ, individual requirements will be listed. 
2 Reference Documents 
This section lists the applicable reference documents and defines the order of preference. 
2.1 Applicable Documents 
Table 1 lists the documents that form a part of this specification to the extent specified herein. 
Table 1: Applicable Documents 
Reference Description 
ANSI C63.4 – 
2009 
“American National Standard for Methods of Measurement of Radio-Noise 
Emissions from Low-Voltage Electrical and Electronic Equipment in the Range of 9 
kHz to 40 GHz.”  American National Standards Institute (ANSI), 2009. 
Australian 
Communications 
& Media 
Authority 
Electromagnetic Compatibility Framework – Information for Suppliers – 
Residential, Commercial and Light Industry”(and amendments), July 1995, URL: 
http://www.acma.gov.au 
C.I.S.P.R. Pub.  22 
 
“Limits and methods of measurement of radio interference characteristics of 
information technology equipment.”  International Special Committee on Radio 
Interference (C.I.S.P.R.), Fifth Edition, 2005+A1. 



 
2 January 20, 2015 
 
Reference Description 
CCC EMC “Regulations for Compulsory Product Certification,” China Certification Center, 
URL: http://www.cemc.org.cn. 
CFR 47, Part 15 “Unintentional Radiators”.  Title 47 of the Code of Federal Regulations, Part 15, 
FCC Rules, Radio Frequency Devices, Subpart B. 
CNS14336-1: 
2010 
“Information technology equipment – Safety – General requirements”, Bureau of 
Standard, Metrology and Inspection 
CNS13438 (2006) 
“LImits and Methods of Measurement of Radio Interference Characteristics of 
Information Technology Equipment”, Bureau of Standard, Metrology and 
Inspection 
EN 55022 
“Limits and methods of measurement of radio interference characteristics of 
information technology equipment.”  European Committee for Electro technical 
Standardization (CENELEC), 2006+A1. 
EN 55024 
“Information technology equipment – Immunity characteristics – Limits and 
Methods of measurement.”  European Committee for Electro technical 
Standardization (CENELEC) 1998 
EN 60320-1 
“Appliance Couplers for Household and Similar General Purposes – Part: General 
Requirements” European Committee for Electro technical Standardization 
(CENELEC). 
EN 60950-1:2005 
A1: 2010 
“Safety of Information Technology Equipment – Safety – Part 1: General 
requirements”, Second Edition, International Electrotechnical Commission, 2005, 
including A1:2010 
EN 60950-1:2006 
A11: 2008 A1: 
2009 
“Safety of Information Technology Equipment – Safety – Part 1: General 
requirements”, Second Edition, European Committee for Electrotechnical 
Standardization (CENELEC), 2006, including A11: 2008 and A1: 2010  
EN 61000-3-
2:2006 
“Electromagnetic Compatibility (EMC) Part 3-2 Limits – Limits for Harmonics 
Current Emissions (Equipment input current 16A per phase).”  International 
Electrotechnical Commission, 2006. 
EN61000-3-3 
“Electromagnetic compatibility (EMC) – Part 3-3 Limits – Limitation of voltage 
fluctuations and flicker in low-voltage supply systems for equipment with rated 
current <= 16 A” European Committee for Electrotechnical Standardization 
(CENELEC), 2008 
GB4943-2001 “Safety of Information technology equipment”, Standardization Administration of 
China 
IEC 60950-1: 
2005 A1: 2010 
“Safety of Information Technology Equipment – Safety – Part 1: General 
requirements”, Second Edition, International Electrotechnical Commission, 2005 
including A1:2010 
IEC 61000-4 
Sections 2 – 6, 11 
“Electromagnetic Compatibility (EMC) – Part 4: Testing and measurement 
techniques.”  International Electro technical Commission (IEC). 



Open Compute Project  Open CloudServer OCS Power Supply 
http://opencompute.org 3 
 
Reference Description 
IPC-A-610 “Specification, Acceptability of Electronic Assemblies.” 
MIL HDBK 217F “Reliability Prediction of Electronic Equipment.”  U.S. Military Standard. 
Taiwan EMC Law 
“Commodity EMC Regulation” (Taiwan EMC Law), Bureau of Standards, 
Metrology, and Inspection under auspices of the Ministry of Economic Affairs, 
URL:http://www.bsmi.gov.tw . 
UL 60950-1 
CSA C22.2 No. 
60950-1-07 
“Safety of Information Technology Equipment including Electrical Business 
Equipment, First Edition.”  Underwriters Laboratories, Inc., 2007, Canadian 
Standards Association, 2007. 
CSA C22.2 
No.107.3-
05,2nded  UL 
1778, 4th ed 
“Uninterruptible Power Systems.”, Underwriters Laboratories, Inc., 2005, 
Canadian Standards Association, 2005. 
UL 60950-1 
CSA C22.2 No. 
60950-1 
"Safety of Information Technology Equipment including Electrical Business 
Equipment, Second Edition." Underwriters Laboratories, Inc., 2007, Canadian 
Standards Association, 2007. 
CAN/CSA - C22.2 
NO. 107.1-01  
“General Use Power Supplies Industrial Products, First Edition.” Canadian 
Standards Association, 2001. 
CAN/CSA - C22.2 
NO. 107.3-05 
“Uninterruptible Power System” (Bi-National standard, with UL 1778), Canadian 
Standards Association, 2005. 
2.2 Order of Preference 
In the event of a conflict between this specification and references cited herein, this specification shall 
take precedence. 
3 Electrical Specification 
This section details the electrical specification. 
3.1 AC Input 
This section describes the AC input. 
3.1.1 Voltage, Current, and Frequency 
The power supply shall operate within all specified limits over the following input voltage range as 
defined in Table 2. 
Table 2: AC Input Rating 



 
4 January 20, 2015 
 
Parameter Min Rated Max 1600WPSU max input current  
at min Vrms  
Voltage (240) 180 Vrms 200-240 Vrms 264 Vrms 
11.0Arms 
Frequency 47 Hz  63 Hz 
3.1.2 Hold-Up Time 
This section defines the hold-up time for version 1 and version 2. 
3.1.2.1 Version 1 
The power supply shall maintain output voltage at 100% rated load for 20ms after an AC Line drop. An 
AC Line dropout is defined as input voltage drooping below minimum voltage thresholds as defined in 
table 1 down to 0VAC for an indefinite amount of time. An AC Line dropout shall not cause an AC line 
breaker to open. For line drops of less than 20ms the power supply shall operate normally. For line 
drops greater than 20ms the power supply may shutdown and then shall recover and turn on normally 
consistent with turn on requirements specified in this document. 
3.1.2.2 Version 2 
The power supply and LES shall maintain output voltage at 100% rated load for 35 seconds and a no less 
than 10 second walk in period after an AC Line drop. An AC Line dropout is defined as the input voltage 
dropping below the minimum voltage thresholds as defined in Table 1 down to 0VAC for a time less than 
40 seconds.  
For dropouts greater than 35 seconds, if battery capacity is available, the power supply shall continue to 
operate up to 40 seconds.  If AC is returned in this time period, no walk is required.  At the 40 second 
mark, if power has not returned the power supply shall latch off.  
An AC Line dropout shall not cause input current to exceed 120% of maximum rated steady state input 
current. For line drops of 0.00 seconds to 40 seconds, the power supply shall operate normally. For line 
drops greater than 40 seconds, the power supply shall shutdown and if so shall recover and turn on 
normally consistent with turn on requirements specified in this document. 
This requirement applies to 6 power supplies in parallel (refer to section 4.3.15 for details). 
3.1.3 AC Turn On Requirement 
This section describes the AC turn on requirement for version 1 and version 2 with batteries disabled. 
The power supply shall return to normal power up state after a slow recovery condition.  The recovery 
shall be tested in all valid redundant power system configurations. With the test loads configured for 
1600W system DC output in resistive mode, the AC line voltage shall be increased from 0VAC to 
180VAC/60Hz at a constant rate over  30 minutes. When VAC input is within proper range the PSU shall 
turn on and assume full load consistent with the soft start requirements. Additional turn on 
requirements for Version 2 are listed in the LES portion of this specification. 



Open Compute Project  Open CloudServer OCS Power Supply 
http://opencompute.org 5 
 
Note: Maximum total load for 1-6 power supplies in parallel is 1600W. 
3.1.4 AC Turn Off Brownout Requirement 
This section describes the AC turn off brownout requirement for version 1 and version 2 with batteries 
disabled. 
The power supply shall return to normal power up state after a slow brownout condition.  The brownout 
condition shall be tested with all valid redundant power system configurations using the end use 
system/s.  While the power system is operating at full rated DC load, the AC line voltage shall be 
reduced from 180VAC/60Hz to 0VAC at a constant rate over a period of 30 minutes.  The power shall be 
then reapplied at 180VAC/60Hz.  
When VAC input is within proper range the PSU shall turn on and assume full load consistent with the 
soft start requirements. This requirement applies to single power supplies only. 
3.1.5 AC Line Fuse 
The AC Line Fuse shall be acceptable for all safety agency requirements. The fuse shall be fast blow type. 
The fuse shall not blow unless component failure is encountered. The fuse shall not blow under all line 
and load conditions. 
The AC Line Fuse shall be rated at 12.5A and shall be part number (or Microsoft approved equivalent): 
CONQUER ELECTRONICS  UBM-A 12.5 
HOLLYLAND    50CF(P)-125H 
 
3.1.6 AC Inlet Connector 
The power supply shall contain IEC C14 connector. 
3.1.7 Input Leakage Current 
Maximum input leakage for a single power supply shall be less than 2.0mA at 240VAC.  
The typical deployment shall be N+1=6 PSU in parallel per WCS chassis with two WCS per power cord for 
a total of 12 PSU per power cord. 
3.1.8 Input Power Rating 
The power supply shall be rated for 1900W input power at 200VAC input. 
3.1.9 Inrush Current 
AC line inrush current shall not exceed 40A peak at all line and load conditions for maximum of 5 msec. 
after application of AC input. Measurement shall be taken 0.1ms after application of AC input. The 
inrush current shall not exceed the 50% I2t derating of any component in series with the inrush current. 
The power supply shall meet the inrush requirements for any rated AC voltage, during turn on at any 
phase of AC voltage, during hot plug, during any AC dropout condition, over the specified temperature 



 
6 January 20, 2015 
 
range (Top), and during AC power cycling.  The AC power cycling test condition is defined as cycling the 
AC power off and back on after the power supply has been operating at maximum load and has reached 
thermal stability.   
Version 1: The period between the AC power cycles could be anywhere between 20 ms to 10 seconds. 
During a line drop out situation the peak inrush current may be violated but no damage or reliability 
reduction may occur to any components the power supply. 
 
3.1.10 Power Factor 
The power factor shall be equal to or greater than 0.98 when measured at 240VAC, 47Hz to 63 Hz input.  
Measurement shall be performed with maximum output load and with source impedance of less than 
0.1 Ω.  It is expected that power factor shall be greater than 0.98 at line voltages less than 240VAC at 
maximum output load condition. 
3.1.11 Harmonic Susceptibility 
Harmonic distortion of up to 10% THD must not cause the power supply to go out of specified limits.  
The power supply shall be capable of start-up (power-on) with full rated power load, at line input as low 
as 180VAC. 
The power supply internal circuitry shall limit maximum input current to 150% max rated at all input and 
operating ambient conditions and output fault conditions. 
3.1.12 Modified Sine Waves 
The power supply shall operate when the AC input is a variant of a sine wave such as from a UPS.  The 
output shall remain within regulation under all load conditions under modified sine wave.  Under 
conditions below the power supply may disable the output: 
 Rise time on the input exceeding 2V/us 
 Input voltage zero crossing lasting greater than 4 ms. 
 Peak of the modified sine wave voltages consistently exceeding 375V  
Under modified sine wave conditions the power supply does not need to meet conducted EMI limits and 
harmonics. 
3.1.13 Harmonic Emissions 
The power supply shall incorporate universal input with active power factor correction, which shall 
reduce line harmonics in accordance with IEC EN61000-3-2 and JEIDA MITI standards. It is desired that 
the power supply also meet the THD requirements across the input voltage range shown in Table 3 
below. 
Table 3: THD Requirements 



Open Compute Project  Open CloudServer OCS Power Supply 
http://opencompute.org 7 
 
Output load (% of max output load) Maximum ITHD (%) 
5-20 20 
20-30 10 
30-100 5 
** The Harmonic Content shall be tested at both the single 1xPSU, 5xPSU, 6xPSU, 11xPSU and 12xPSU 
configurations.  The typical deployment shall be N+1=6 PSU in parallel per WCS chassis with two WCS 
per power cord for a total of 12 PSU per power cord. 
3.1.14 Line Transient 
The power supply shall operate within specifications under the following conditions: 
 Transients as defined in IEC 61000-4-4. 
 Transients as defined in IEC 61000-4-5.  
(Up to and including 2 kV limits and phases 0⁰, 90⁰, 180⁰, and 270⁰. 
3.1.15 Electrostatic Discharge Susceptibility 
The power supply shall withstand the following ESD conditions at any point on the power supply 
enclosure.  
 15 kV air discharge with no abnormal operation or damage to power supply 
 Transients as defined in IEC 801-2  
The storage capacitance shall be 150 pF and the discharge resistance shall be 330 ohms.  The power 
supply shall meet all discharge requirements for the CE Mark designation. 
3.1.16 Fast Transient Burst 
The power supply shall comply with the limits defined in EN55024: 1998/A1: 2001/A2: 2003 using the 
IEC 61000-4-4: Second edition: 2004-07 test standard and performance criteria B defined in Annex B of 
CISPR 24. 
3.1.17 Radiated Immunity 
The power supply shall comply with the limits defined in EN55024: 1998/A1: 2001/A2: 2003 using the 
IEC 61000-4-3: Edition 2.1: 2002-09 test standard and performance criteria A defined in Annex B of 
CISPR 24. 
3.1.18 Surge Immunity 
The power supply shall be tested with the system for immunity to AC Unidirectional wave; 2kV line to 
ground and 1kV line to line, per EN 55024: 1998/A1: 2001/A2: 2003, EN 61000-4-5: Edition 1.1:2001-04. 
The pass criteria include: No unsafe operation is allowed under any condition; all power supply output 
voltage levels to stay within proper spec levels; No change in operating state or loss of data during and 
after the test. 



 
8 January 20, 2015 
 
3.1.19 Efficiency 
The power supply shall meet the efficiency requirements given in Table 4.   
** Efficiency is important and cost effective efficiency improvements shall be evaluated before the 
power supply design is finalized. The typical load range will be 50%- 80% PSU loading and 95% under 
system fault conditions. Special consideration will be given for efficiency improvements in this area of 
operation.  Fan can be powered externally for efficiency test. 
Table 4: Efficiency 
Input voltage (VAC RMS) Output load (A) Minimum efficiency (%) 
200 26 92 
200 65 92.5 
200 131 91 
208 26 92 
208 65 92.5 
208 131 91 
230 26 92 
230 65 94 
230 131 92.5 
240 26 92 
240 65 94 
240 131 92.5 
3.2 Battery Backup Operation 
This section describes the battery backup operation. Figure 1 shows a basic block diagram of the battery 
backup supply. 
Following are the battery backup requirements. 
1. The LES shall provide sufficient ride through capacity to maintain proper PSU output for 35 
seconds (+/- 500ms) minimum plus walk-in period of no less than 10 seconds (+/- 500ms).  
The power supply shall meet the reliability and operating life with drop outs at a maximum 
power of 1600W for 5 seconds then reducing to 1425W for the remainder of the drop out.  
The power supply shall be capable of operating at greater than 1425W to 1600W 
continuous drop out but reliability and operating life of the battery are not guaranteed.  



Open Compute Project  Open CloudServer OCS Power Supply 
http://opencompute.org 9 
 
The power supply shall switch to battery power upon loss of input AC or PH_LOSS signal 
going low. 
a. Walk-in is defined as the action or reloading the AC line incrementally after 
operating on battery power.  
i. Walk-in shall occur after being on battery power for more than 500ms up 
to 35 seconds. 
ii. The walk-in ramp shall not present input power steps greater than 200W 
per second on the AC line over the specified walk-in period. The walk-in 
period shall not be less than 10 seconds. The Walk-in functionality shall be 
present from LES to line cord transition over the life of the deployment.  
b. Upon loss of AC or PH_LOSS going low, the power supply shall switch to internal 
battery power until AC returns or PH_LOSS goes high up to 40 seconds. After 35 
seconds the power supply is not required to perform a walk in. If AC has not 
returned by the 40 second mark, the power supply shall latch off.   
c. PH_LOSS special condition.  If PH_LOSS is still low after 40 seconds and valid AC is 
present, the power supply shall return to AC power.  The power supply shall ignore 
PH_LOSS until PH_LOSS goes Hi again at which point the power supply shall behave 
normally.  If AC is lost while PH_LOSS is low the power supply shall go to battery as 
described in paragraph 5.1.1.1. 
2. Partial discharge duty cycle shall be 4 discharges per year at a 5 second discharge with a 
walk-in period of no less than 10 seconds from LES to line cord transition.  
3. Full discharge duty cycle shall be 1 discharge per 2 years at a 35 second discharge with a 
walk-in period of no less than 10 seconds from LES to line cord transition. 
4. The LES shall be capable of withstanding multiple outages lasting 35 seconds plus a walk-in 
period of no less than 10 seconds. The worst case AC fault with minimum recharge period is 
4consecutive outages with 60 minute recharge between outages. Figure 1 shows the timing 
diagram. 
 
Figure 1: Timing diagram 
 


 
10 January 20, 2015 
 
5. The power supply shall be capable of, when given the command via PMBUS, to go to 
battery power for one to three seconds then return to AC power. This is to check for weak 
or bad cells within the battery pack.  See firmware section 9 for specific command 
description and register location. 
6. Extended Battery Operation.  The power supply shall be capable of running off of battery 
when set to extended battery operation.  When set to extended battery operation, the 
power supply shall look at output power at 37 +/- 1 seconds after AC loss and if output 
power is less than 75W, the power supply shall continue to run off of battery for 200 
seconds.  If power increases above 100W output during that time the 12V output shall be 
disabled within 1 second.  If AC returns during the extended battery operation the power 
supply shall return to AC mains with no walk in required. 
 
3.3 DC Outputs, Signal Outputs, and Control Outputs 
This section describes the DC outputs. 
3.3.1 Output Power and Current 
Across the nominal input voltage range, the PSU output power shall be as specified in Table 5. The 
power supply shall meet static and dynamic voltage regulations requirements across the load range. 
Table 5: Output Power and Current 
Power supply unit Output Min Max Unit 
1600W base and LES 12.25VDC 0.1 131 A 
3.3.2 Output ORing 
For fault tolerance, the power supply shall contain output ORing functionality. 
3.3.3 Standby Output 
The power shall not provide a standby output. 
3.3.4 Setpoint 
The voltage setpoint shall be as specified in Table 6. 
Table 6: Setpoints 
Parameter Min Set point nominal Max Units Current (A) 
+12V 12.20  12.25 12.30 Vrms 60 



Open Compute Project  Open CloudServer OCS Power Supply 
http://opencompute.org 11 
 
3.3.5 Static Voltage Regulation 
The output voltage regulation output must stay within the following voltage limits when operating at all 
load and input line voltages across the ambient temperature limits under steady state conditions. 
Table 7: Static Voltage 
Parameter Min Set point nominal Max Units 
+12V 12.00  12.25 12.50 Vrms 
3.3.6 Ripple and Noise 
The maximum allowed ripple/noise output of the power supply is defined in 120mVp-p. This is 
measured over a bandwidth of 10Hz to 20MHz at the power supply output connectors. A 10uF tantalum 
capacitor in parallel with a 0.1uF ceramic capacitor is placed at the point of measurement. 
3.3.7 Dynamic Load Step 
The output voltages shall remain within Dynamic voltage limits specified for the step loading and 
capacitive loading specified below. The load transient repetition rate shall be tested between 50Hz and 
5kHz at duty cycles ranging from 10%-90%. The load transient repetition rate is only a test specification. 
The delta step load may occur anywhere within the MIN load to the MAX load conditions. Dynamic 
voltage limits are 11.64VDC-12.86VDC. 
Table 8: Dynamic Load Step 
Output Delta step load Transient load rate  Capacitance test load 
+12V 
60% of maximum rated load 
1%-61% and 40% to 100% 
0.25A/usec 3500uF +/-5% 
3.3.8 Capacitive Loading 
The power supply shall be stable and meet all requirements with the following capacitive loading 
ranges. 
Table 9: Capacitive Loading 
Output Min Max Units 
+12V 200 22000 uF 
3.3.9 Closed Loop Stability 
The power supply shall be unconditionally stable under all line/load/transient load conditions including 
capacitive load ranges specified in Section 4.6. A minimum of: 45 degrees phase margin and -10dB-gain 
margin is required. The power supply manufacturer shall provide proof of the unit’s closed-loop stability 
with local sensing through the submission of Bode plots. Closed-loop stability must be ensured at the 
maximum and minimum loads as applicable. 



 
12 January 20, 2015 
 
3.3.10 Grounding 
The output ground of the pins of the power supply provides the output power return path. The output 
connector ground pins shall be connected to the safety ground (power supply enclosure). This grounding 
should be well designed to ensure passing the max allowed Common Mode Noise levels. 
The power supply shall be provided with a reliable protective earth ground. All secondary circuits shall 
be connected to protective earth ground. Resistance from the input receptacle to chassis shall not 
exceed 100 mΩs.  This shall be tested 100%. 
3.3.11 Common Mode Noise 
The Common Mode noise on any output shall not exceed 350mV pk-pk over the frequency band of 10Hz 
to 20MHz. The measurement shall be made across a 100Ω resistor between each of DC outputs, 
including ground at the DC power connector and chassis ground (power subsystem enclosure). 
3.3.12 Soft Start 
The Power Supply shall contain control circuit which provides monotonic soft start for its outputs 
without overstress of the AC line or any power supply components at any specified AC line or load 
conditions. 
3.3.13 Zero Load Stability 
When the power subsystem operates in a no load condition, it does not need to meet the output 
regulation specification, but it must operate without any tripping of over-voltage or other fault circuitry. 
When the power subsystem is subsequently loaded, it must begin to regulate and source current 
without fault. Continuous operation at no load shall not damage or reduce reliability of the power 
supply. 
3.3.14 Hot Swap Requirements 
Hot swapping a power supply is the process of inserting and extracting a power supply from an 
operating power system. During this process the output voltages shall remain within the limits with the 
capacitive load specified. The hot swap test must be conducted when the system is operating under 
static, dynamic, and zero loading conditions. The power supply shall use a latching mechanism to 
prevent insertion and extraction of the power supply when the AC power cord is inserted into the power 
supply. 
3.3.15 Forced Load Sharing 
The +12V output will have active load sharing. The output will share within 5% from 35% load to 75% 
load and 3% from 75% to 100% full load in a configuration of 4, 5 and 6 power supplies in parallel. Below 
35% load the power supplies shall share within 5.0 amps output current of each other. The failure of a 
power supply should not affect the load sharing or output voltages of the other supplies still operating. 
The supplies must be able to load share in parallel and operate in a hot-swap / redundant 1+1 
configurations. 



Open Compute Project  Open CloudServer OCS Power Supply 
http://opencompute.org 13 
 
4 PSU System Interconnect 
This section describes the PSU system interconnect. 
4.1 Remote On/Off 
The PSU shall be ON when PS_ON is pulled low below 0.8VDC at 1mA or less source current. The PSU 
shall be powered off when driven to 2.06VDC or higher. 
Table 10: Power On/Off 
Signal 
name 
Input/ 
output 
to PSU 
Open 
collector 
3V3 
logic 
Signal 
pull up 
resistor 
value 
Logic 
low 
max 
(V) 
Logic 
high 
min 
(V) 
Sink/ 
source 
current 
max 
Rise 
time 
max 
(nsec) 
Fall 
time 
max 
(nsec) 
Cmax 
external 
to PSU 
Peak 
noise 
(mVpk-
pk) 
PS_On In NO  YES  NA 0.8 2.06 N/A 100 100  no 250 
4.2 Power Good Signal 
The POK signal shall be high when the PSU is operating normally. The POK shall be low when the PSU 
cannot maintain current for specified proper voltage regulation. POK can be a combination of voltage 
inside the or’ing diode/FET or detection of loss of switching or other fault indicating that the power 
supply cannot provide proper output voltage and current. The open collector/drain signal shall be 
capable of driving the output below 0.4V with a 10mA source current.  The POK signal shall go low 
within 1.5ms of output voltage dropping to 11.6V or below.  POK will go HI within 200ms of the 12V 
output being in regulation. 
Table 11: Power Good 
Signal 
name 
Input/ 
output 
to PSU 
Open 
collector 
3V3 
logic 
Signal 
pull up 
resistor 
value 
Logic 
low 
max 
(V) 
Sink/ 
source 
current 
max 
(mA) 
Rise 
time 
max 
(usec) 
Fall 
time 
max 
(usec) 
Peak 
noise 
(mVpk-
pk) 
POK Out YES YES 
1k +/-
5% 0.4 10  200  100 <400 
4.3 Fan Speed Control 
The PSU shall adjust internal fan speed based upon internal temperature sensor(s). The PSU shall adjust 
fan speed to maintain component temperatures internal to the power supply below derated 
temperature limits. The fan speed algorithm shall attempt to use as little fan power as possible to keep 
components within derated limits. The power supply should latch off in the event of a blocked rotor or 
failed fan.  



 
14 January 20, 2015 
 
4.4 VIN_Good Signal 
The VIN_Good Signal shall go low when VAC input falls outside the specified operation range. The signal 
must have hysteresis to prevent oscillations during AC noise or hash.  The output shall be open 
collector/drain and be capable of driving the output below 0.4V with a load of 4mA. The output shall 
have an internal input pull up resistor of 1kohm between 3.3VDC. 
Table 12: VIN_Good Signal 
Signal 
name 
Input/ 
output 
to PSU 
Open 
collector 
3V3 
logic 
Signal 
pull up 
resistor 
value 
Logic 
low 
max 
(V) 
Logic 
high 
min 
(V) 
Sink/ 
source 
current 
max 
(mA) 
Rise 
time 
max 
(usec) 
Fall 
time 
max 
(usec) 
Cmax 
external 
to PSU 
(pF) 
Peak 
noise 
(mVpk-
pk) 
Vin_G
ood Out YES YES 1k +/-
5% 0.4   4 2.5 2.5 330 <400 
4.5 I-Share 
-Share is a common bus used for active current sharing of the power supplies.  Refer to section 4.3.15 
for sharing requirements. 
The Ishare voltage shall be 0V at no load and rise linearly to 7V at full load output. The accuracy shall be 
tight enough to meet the sharing requirements of paragraph 4.3.15 
4.6 I2C/PMBus 
Table 13: I2C/PMBus 
Signal 
name 
Input/ 
output 
to PSU 
Open 
collector 
3V3 
logic 
Signal 
pull up 
resistor 
value 
Logic 
low 
max 
(V) 
Logic 
high 
min 
(V) 
Sink/ 
source 
current 
max 
(mA) 
Rise 
time 
max 
(usec) 
Fall 
time 
max 
(nsec) 
Cmax 
external 
to PSU 
(pF) 
SDA I/O NO YES 6.81K 
+/-20% 0.8 2.0 6 1 250 120 
SCL I/O NO YES 6.81K 
+/-20% 0.8 2.0 6 1 250 120 
Alert Out YES YES 100k 
+/-20% 0.8 2.0 N/A 1 250   
4.7 PS_KILL/EPO 
PS Kill is used to disable the output when the Power Supply is being extracted from the system chassis 
and to keep the outputs disabled when the power supply is not inserted.  When PS_Kill goes hi (>2.0V), 



Open Compute Project  Open CloudServer OCS Power Supply 
http://opencompute.org 15 
 
the output converter shall stop switching within 500us.  PS_Kill is pulled up in the power supply to 3.3V 
and will be pulled low in the system chassis by a 100 Ohm resistor. 
Table 14: PS_Kill 
Signal 
name 
Input/ 
output 
to PSU 
Open 
collector 
3V3 
logic 
Signal 
pull up 
resistor 
value 
Logic 
low 
max 
(V) 
Logic 
high 
min 
(V) 
Sink/ 
source 
current 
max 
(mA) 
Rise 
time 
max 
(usec) 
Fall 
time 
max 
(usec) 
Cmax 
external 
to PSU 
(pF) 
Peak 
noise 
(mVpk-
pk) 
PS_Kill
_EPO In NO yes  10KOh
m  0.4 2.0V or 
NC 0.5  250  2.5  0 250mV 
4.8 PSU Alert 
The signal shall be high until status change of the PSU. The signal shall remain low until the port is read 
or contents of register returns to original state.  
Table 15: PSU Alert 
Signal 
name 
Input/ 
output 
to PSU 
Open 
collector 
3V3 
logic 
Signal pull up 
resistor value 
Logic 
low 
max 
(V) 
Logic 
high 
min 
(V) 
Sink 
current 
max 
(mA) 
Rise 
time 
max 
(usec) 
Fall time 
max 
(usec) 
Cmax 
external 
to PSU 
(pF) 
Peak 
noise 
(mVpk-
pk) 
Alert Out YES YES 100k +/-20% 0.8V 2.0V Note 1 1usec 250nsec   250mV 
Note 1: Pull up to 3.3V through 100K ohms 
4.9 Power Supply Present 
The PS_PRESENT signal shall be tied to return via 100ohm resistor in the power supply and be sized for 
connection to 3.3VDC. This signal is pulled up to 3.3VDC via a WCS system 8.2kohm resistor. The signal 
shall be tied to ground with a series 100 ohm resister. 
Table 16: PS_Present 
Signal name 
Input/ 
output 
to PSU 
Open 
collector 
3V3 
logic 
Signal 
pull up 
resistor 
value 
Logic 
low 
max 
(V) 
Logic 
high 
min 
(V) 
Sink/ 
source 
current 
max 
(mA) 
Rise 
time 
max 
(usec) 
Fall 
time 
max 
(usec) 
Cmax 
external 
to PSU 
(pF) 
Peak 
noise 
(mVpk-
pk) 
PS_Present Out No                 250mV 
4.10 Phase Loss Detect 
PH-Loss is a common bus used to detect the loss of AC input on two or more power supplies in parallel 
in a system.  The bus is set at 3.32V via resistor divider on the power backplane of 22.1Kohm and 
8.2Kohm.  When an AC loss is detected the power shall pull down on this bus via 10Kohm resistor to 



 
16 January 20, 2015 
 
ground. The power supply shall monitor this bus so that if the signal drops below the trip level of 1.79V 
the power supply shall immediately go to battery power until the signal rises above 1.84V or 40 seconds 
have elapsed on battery power in which case the power supply shall return to AC power. 
4.11 Output Connector Pinout 
The mating output connector shall be a 64 pin receptacle, 2 vertical row, 2.54 Pitch, FCI 10046971-001LF 
or Microsoft approved equivalent. 
 
Figure 2: Output connector pinout 
4.12 Protection Circuits 
Protection circuits inside the power supply shall cause only the power supply’s main outputs to 
shutdown. The PSU shall to continue operating under a fault protection condition and provide 
communication via I2C to the system.  Loss of internal communication shall be a condition for latching 
off the output.  
When a protection circuit shuts down the power supply, green LED shall change to solid yellow if able 
otherwise unlighted status. 


Open Compute Project  Open CloudServer OCS Power Supply 
http://opencompute.org 17 
 
4.12.1 Over Current Limit (OCL) 
The power supply shall provide limited output current to the load for protecting the power supply from 
damage under indefinite over load conditions. OCL shall be set between 115% and 130% of rated output 
current. Under an overcurrent condition for over 200ms, the power supply shall employ hiccup mode 
(20ms on and 2 seconds off) for 5 cycles and if overcurrent isn’t cleared after the 5th cycle, the power 
supply shall latch off (All timing accuracy above is +/- 20%). 
4.12.2 Over Voltage Protection (OVP) 
The power supply over voltage protection shall be shutdown in a latch off mode upon an over voltage 
condition.  Over voltage is range is 13.6VDC to 15VDC. 
4.12.3 Over Temperature Protection (OTP) 
The power supply shall be protected against over temperature conditions caused by loss of fan cooling 
or excessive ambient temperature which could cause internal part failures.   In an over temperature 
condition the PS shall shutdown protecting itself. When the temperature drops to within safe operating 
limit for internal parts, the power supply shall restore power automatically.  The OTP circuit shall 
incorporate built in hysteresis such that the power supply does not oscillate on and off due to 
temperature recovering condition.  The OTP event shall be reported as a fault condition. 
5 LED Indicators 
Following are the LED indicators and power supply LED States: 
 Power supply LED configuration 
The power supply may have a single bi-color (Green-Yellow) configuration. 
 Power supply LED states 
Single bi-colored LED configuration: 
o AC_OK & DC_OK (Power Good: Solid Green (Bi-color LED) 
o Fault (fault of any kind): Solid Yellow (Bi-color LED) 
o Internal Battery Charging: Continuous Blinking green 
o Operating off internal battery: Continuous blinking yellow 
Following is more detail about the LED indicators: 
 Fault indicator 
This Bi-Color (Green-Yellow) LED is driven by internal circuitry and will illuminate yellow 
when a power rail has failed, or –FAN_FAULT is low. The LED should not be illuminated if 
the supply turns off due to PS_KILL. The LED will illuminate even if the power supply is in a 
latched state.  
3mm Green-Yellow, Bi-color, LED applications: SunLed: XLUGY34M or Kingbright: 
WP3WGYW or Microsoft approved equivalent. 
Note: LED’s should be biased with a forward current (If) of 6 mA. 



 
18 January 20, 2015 
 
 Power Good indicator 
This Bi-Color Green-Yellow LED is driven by internal circuitry and will illuminate whenever 
POWER GOOD is asserted.  
 AC Good indicator 
This green LED is driven by internal circuitry and will illuminate whenever VIN_GOOD is 
asserted. 
 Operating on internal battery 
The Yellow LED will turn on and off at a 2 Hz rate whenever the power supply is operating 
from internal battery power. 
 Internal battery charging 
The green LED will turn on and off at a 2 Hz rate when the internal battery is charging.  This 
shall not occur during maintenance or top off charge. 
6 Mechanical Specifications 
This section describes the mechanical specifications. 
6.1 Dimensions 
The power supply is held into the chassis using a chassis-mounted latch.  The latch hooks on to the 
power supply using the latching notches detailed in the drawing.   
A handle or hook feature is required on the front surface of the supply to allow for removal from the 
server.  The handle may be hinged in order to rotate away when not needed as long as it does not 
interfere with the power cable location.  All features of the power supply, including the handle, fans, 
connectors and anything else must be within the dimensions shown in the drawing when in use in the 
server. 
The power chord must attach to the plug on the surface shown to allow for power cord connector 
clearance at the back of the server. 
 
Figure 3: Dimension detail (side) 


Open Compute Project  Open CloudServer OCS Power Supply 
http://opencompute.org 19 
 
 
Figure 4: Additional detail 
6.2 Core Handle Retention 
A latch or Microsoft approved equivalent on the power supply is required to provide retention of the AC 
power cord. 
6.3 Electrostatic Discharge 
The power supply shall withstand the following ESD conditions at any point on the power supply 
enclosure.  
 8 kV with no abnormal operation, air discharge. 
 8 kV with no damage to the power supply, air discharge. 
 Transients as defined in IEC 801-2, Level 4 
The storage capacitance shall be 150 pF and the discharge resistance shall be 330 Ωs. The tsupply shall 
meet all discharge requirements for the CE Mark designation. 
7 Agency Approvals and Product Regulatory 
Requirements 
This product was evaluated as Information Technology Equipment (ITE), which may be installed in 
offices, schools, computer rooms, and similar commercial type locations. The suitability of this product 
for other product categories and environments (such as: medical, industrial, telecommunications, NEBS, 
residential, alarm systems, test equipment, etc.), other than an ITE application, may require further 
evaluation. 


 
20 January 20, 2015 
 
7.1 Safety Requirements and Approvals 
The following are the product safety compliance regulations that must be net: 
 UL60950-1/CSA 60950-1 (USA / Canada) 
 EN60950-1 (Europe) 
 IEC60950-1 (International) 
 CB Certificate & Report, IEC60950-1 (report to include all country national deviations) 
 Nordics – EMKO-TSE (74-SEC) 207/94 
 CE - Low Voltage Directive 2006/95/EC (Europe) 
 GB4943- CNCA Certification (China) 
7.2 EMC Requirements and Approvals 
The power supply and LES shall be approved/licensed/certified as specified below.  Copies of ALL 
approval licenses/certifications for the system shall be provided upon request.  
 Certifications / Registrations / Declarations 
 UL Certification (US/Canada) 
 CB Certificate & Report 
 CE Declaration of Conformity (CENELEC Europe) 
 FCC/ICES-003 Class A Attestation (USA/Canada) 
 C-Tick/MED Declaration of Conformity (Australia/New Zealand) 
 CNCA Certification (China) 
 Ecology Declaration (International) 
Note: Certification shall be done to the most recent standard editions 
7.3 Component Regulation Requirements 
Following are the component regulation requirements: 
 All Fans shall have the minimum certifications: UL and TUV or VDE. 
 All current limiting devices shall have UL and TUV or VDE certifications and shall be suitable 
rated for the application where the device in its application complies with IEC60950. 
 All printed wiring boards shall be rated UL94V-0 and be sourced from a UL approved 
printed wiring board manufacturer. 
 All connectors shall be UL recognized and have a UL flame rating of UL94V-0. 
 All wiring harnesses shall be sourced from a UL approved wiring harness manufacturer. 
SELV Cable to be rated minimum 80V, 130C. 
 Product safety label must be printed on UL approved label stock and printer ribbon. 
Alternatively labels can be purchased from a UL approved label manufacturer. 



Open Compute Project  Open CloudServer OCS Power Supply 
http://opencompute.org 21 
 
 The product must be marked with the correct regulatory markings to support the 
certifications that are specified in this document. 
7.4 Product EMC Compliance 
The product is required to comply with Class A emission requirements as the end system that it is 
configured into is intended for a commercial environment and market place. The power supply is to 
have minimum of 6db margin to Class A. 
 FCC /ICES-003 - Emissions (USA/Canada) Verification 
 CISPR 22 – Emissions (International) 
 EN55022 - Emissions (Europe) 
 EN55024 - Immunity (Europe) 
o EN61000-4-2 Electrostatic Discharge 
o EN61000-4-3 Radiated RFI Immunity 
o EN61000-4-4 Electrical Fast Transients 
o EN61000-4-5 Electrical Surge 
o EN61000-4-6 RF Conducted 
o EN61000-4-8 Power Frequency Magnetic Fields 
o EN61000-4-11 Voltage Dips and Interruptions 
 *EN61000-3-2 - Harmonics (Europe) 
 *EN61000-3-3 - Voltage Flicker (Europe) 
 CE – EMC Directive 89/336/EEC (Europe) 
 JEIDA (Japan) 
7.5 Markings and Identification 
The power supply module nameplate label(s) shall have the following markings at a minimum. 
 Supplier’s Company  
 Regulatory Model Number (RMN)  
 supplier’s Generic Part Number:  
 supplier’s Part Number:  
 supplier’s Spares Part Number:   
 Supplier Revision level 
 Supplier Date Code of manufacture 
 Commodity Tracking Label, OEM Sub-Assemblies  
 Assembly Codes for this supply Country of Manufacture 
 All Required AGENCY MARKINGS  
 Multi-Lingual Hazardous Cautionary marking 
 Electrical Rating:  Output rating, Input rating in Volts, Amps, Hertz. 
 Hipot marking 



 
22 January 20, 2015 
 
 Electric shock warning (lightning bolt marking) 
 Crossed out screw driver marking 
 All required environmental markings  
 